# S9S_MB_2U (Grand Teton) — schematic netlist excerpt (pin names and nets, part order shuffled) for the footprints in the layout excerpt that follows; sources: Cadence DE-HDL packaged netlist, KiCad conversion of 03242023_DA0F0TMBIJ0_F0T_Motherboard_J_brd_V01_OCP.brd

PC385  Q_CAPP  560UF 2.5V 20% OSCON  pkg THLF  page 297 : A = PVCCD_HV_CPU1 ; B = GND
PC2081  Q_CAP  10UF 16V 10% X6S  pkg C0805  page 156 : A = P3V3_OCP_SFF_R ; B = GND
R3645  Q_RES  0.01 1% CHIP  pkg 2512LF  page 171 : A = P3V3_OCP_SFF ; B = P3V3_OCP_SFF_R

(kicad_pcb
	(version 20260206)
	(generator "pcbnew")
	(generator_version "10.0")
	(general
		(thickness 1.6)
		(legacy_teardrops no)
	)
	(paper "A4")
	(title_block
		(title "03242023_DA0F0TMBIJ0_F0T_Motherboard_J_brd_V01_OCP.brd")
		(comment 1 "Grand Teton / footprints 691-693 of 6105")
	)
	(layers
		(0 "F.Cu" signal "TOP")
		(4 "In1.Cu" signal "GND")
		(6 "In2.Cu" signal "IN1")
		(8 "In3.Cu" signal "GND1")
		(10 "In4.Cu" signal "IN2")
		(12 "In5.Cu" signal "GND2")
		(14 "In6.Cu" signal "IN3")
		(16 "In7.Cu" signal "GND3")
		(18 "In8.Cu" signal "VCC")
		(20 "In9.Cu" signal "VCC1")
		(22 "In10.Cu" signal "GND4")
		(24 "In11.Cu" signal "IN4")
		(26 "In12.Cu" signal "GND5")
		(28 "In13.Cu" signal "IN5")
		(30 "In14.Cu" signal "GND6")
		(32 "In15.Cu" signal "IN6")
		(34 "In16.Cu" signal "GND7")
		(2 "B.Cu" signal "BOTTOM")
		(9 "F.Adhes" user "F.Adhesive")
		(11 "B.Adhes" user "B.Adhesive")
		(13 "F.Paste" user "Package Geometry/Pastemask Top")
		(15 "B.Paste" user "Package Geometry/Pastemask Bottom")
		(5 "F.SilkS" user "Ref Des/Silkscreen Top")
		(7 "B.SilkS" user "Ref Des/Silkscreen Bottom")
		(1 "F.Mask" user "Board Geometry/Soldermask Top")
		(3 "B.Mask" user "Board Geometry/Soldermask Bottom")
		(17 "Dwgs.User" user "User.Drawings")
		(19 "Cmts.User" user "User.Comments")
		(21 "Eco1.User" user "User.Eco1")
		(23 "Eco2.User" user "User.Eco2")
		(25 "Edge.Cuts" user "Board Geometry/Outline")
		(27 "Margin" user)
		(31 "F.CrtYd" user "Package Geometry/Place Bound Top")
		(29 "B.CrtYd" user "Package Geometry/Place Bound Bottom")
		(35 "F.Fab" user "Ref Des/Assembly Top")
		(33 "B.Fab" user "Ref Des/Assembly Bottom")
	)
	(footprint ""
		(layer "F.Cu")
		(at 430.827434 -98.175064 180)
		(property "Reference" "R3645"
			(at 0 0 180)
			(layer "F.SilkS")
			(hide yes)
			(effects
				(font
					(size 1.27 1.27)
				)
			)
		)
		(property "Value" ""
			(at 0 0 180)
			(layer "F.Fab")
			(effects
				(font
					(size 1.27 1.27)
				)
			)
		)
		(duplicate_pad_numbers_are_jumpers no)
		(fp_line
			(start 4.0386 1.7526)
			(end -4.0386 1.7526)
			(stroke
				(width 0.1524)
				(type default)
			)
			(layer "F.SilkS")
		)
		(fp_line
			(start 4.0386 -1.7526)
			(end 4.0386 1.7526)
			(stroke
				(width 0.1524)
				(type default)
			)
			(layer "F.SilkS")
		)
		(fp_line
			(start -4.0386 1.7526)
			(end -4.0386 -1.7526)
			(stroke
				(width 0.1524)
				(type default)
			)
			(layer "F.SilkS")
		)
		(fp_line
			(start -4.0386 -1.7526)
			(end 4.0386 -1.7526)
			(stroke
				(width 0.1524)
				(type default)
			)
			(layer "F.SilkS")
		)
		(fp_line
			(start 4.0386 1.7526)
			(end -4.0386 1.7526)
			(stroke
				(width 0.1)
				(type default)
			)
			(layer "F.Fab")
		)
		(fp_line
			(start 4.0386 -1.7526)
			(end 4.0386 1.7526)
			(stroke
				(width 0.1)
				(type default)
			)
			(layer "F.Fab")
		)
		(fp_line
			(start -4.0386 1.7526)
			(end -4.0386 -1.7526)
			(stroke
				(width 0.1)
				(type default)
			)
			(layer "F.Fab")
		)
		(fp_line
			(start -4.0386 -1.7526)
			(end 4.0386 -1.7526)
			(stroke
				(width 0.1)
				(type default)
			)
			(layer "F.Fab")
		)
		(pad "1" smd rect
			(at -3.1115 0 180)
			(size 1.524 3.2004)
			(layers "F.Cu" "F.Mask" "F.Paste")
			(net "P3V3_OCP_SFF")
		)
		(pad "2" smd rect
			(at 3.1115 0 180)
			(size 1.524 3.2004)
			(layers "F.Cu" "F.Mask" "F.Paste")
			(net "P3V3_OCP_SFF_R")
		)
	)
	(footprint ""
		(layer "F.Cu")
		(at 69.923406 -166.634922)
		(property "Reference" "PC385"
			(at 0 0 0)
			(layer "F.SilkS")
			(hide yes)
			(effects
				(font
					(size 1.27 1.27)
				)
			)
		)
		(property "Value" ""
			(at 0 0 0)
			(layer "F.Fab")
			(effects
				(font
					(size 1.27 1.27)
				)
			)
		)
		(duplicate_pad_numbers_are_jumpers no)
		(fp_line
			(start 2.750058 0.999998)
			(end -2.750058 0.999998)
			(stroke
				(width 0.1524)
				(type default)
			)
			(layer "F.SilkS")
		)
		(fp_circle
			(center 0 0.999998)
			(end 2.750058 0.999998)
			(stroke
				(width 0.1524)
				(type default)
			)
			(fill no)
			(layer "F.SilkS")
		)
		(fp_poly
			(pts
				(arc
					(start 2.750058 0.999998)
					(mid 0 3.750056)
					(end -2.750058 0.999998)
				)
			)
			(stroke
				(width 0)
				(type default)
			)
			(fill yes)
			(layer "F.SilkS")
		)
		(fp_circle
			(center 0 0.999998)
			(end 2.750058 0.999998)
			(stroke
				(width 0.1)
				(type default)
			)
			(fill no)
			(layer "F.Fab")
		)
		(pad "1" thru_hole rect
			(at 0 0)
			(size 1.5748 1.5748)
			(drill 1.0668)
			(layers "*.Cu" "*.Mask")
			(remove_unused_layers no)
			(net "PVCCD_HV_CPU1")
			(clearance 0)
			(padstack
				(mode front_inner_back)
				(layer "Inner"
					(shape circle)
					(size 1.5748 1.5748)
					(clearance 0)
				)
				(layer "B.Cu"
					(shape rect)
					(size 1.5748 1.5748)
					(clearance 0)
				)
			)
		)
		(pad "2" thru_hole circle
			(at 0 1.999996)
			(size 1.5748 1.5748)
			(drill 1.0668)
			(layers "*.Cu" "*.Mask")
			(remove_unused_layers no)
			(net "GND")
			(clearance 0)
		)
	)
	(footprint ""
		(layer "F.Cu")
		(at 426.6819 -109.644688 90)
		(property "Reference" "PC2081"
			(at 0 0 90)
			(layer "F.SilkS")
			(hide yes)
			(effects
				(font
					(size 1.27 1.27)
				)
			)
		)
		(property "Value" ""
			(at 0 0 90)
			(layer "F.Fab")
			(effects
				(font
					(size 1.27 1.27)
				)
			)
		)
		(duplicate_pad_numbers_are_jumpers no)
		(fp_line
			(start 1.524 -0.762)
			(end 1.524 0.762)
			(stroke
				(width 0.1524)
				(type default)
			)
			(layer "F.SilkS")
		)
		(fp_line
			(start -1.524 -0.762)
			(end 1.524 -0.762)
			(stroke
				(width 0.1524)
				(type default)
			)
			(layer "F.SilkS")
		)
		(fp_line
			(start 1.524 0.762)
			(end -1.524 0.762)
			(stroke
				(width 0.1524)
				(type default)
			)
			(layer "F.SilkS")
		)
		(fp_line
			(start -1.524 0.762)
			(end -1.524 -0.762)
			(stroke
				(width 0.1524)
				(type default)
			)
			(layer "F.SilkS")
		)
		(fp_line
			(start 1.1049 -0.724916)
			(end -1.1049 -0.724916)
			(stroke
				(width 0.1)
				(type default)
			)
			(layer "F.Fab")
		)
		(fp_line
			(start -1.1049 -0.724916)
			(end -1.1049 0.724916)
			(stroke
				(width 0.1)
				(type default)
			)
			(layer "F.Fab")
		)
		(fp_line
			(start 1.1049 0.724916)
			(end 1.1049 -0.724916)
			(stroke
				(width 0.1)
				(type default)
			)
			(layer "F.Fab")
		)
		(fp_line
			(start -1.1049 0.724916)
			(end 1.1049 0.724916)
			(stroke
				(width 0.1)
				(type default)
			)
			(layer "F.Fab")
		)
		(pad "1" smd rect
			(at -0.889 0 270)
			(size 1.016 1.27)
			(layers "F.Cu" "F.Mask" "F.Paste")
			(net "P3V3_OCP_SFF_R")
		)
		(pad "2" smd rect
			(at 0.889 0 270)
			(size 1.016 1.27)
			(layers "F.Cu" "F.Mask" "F.Paste")
			(net "GND")
		)
	)
)
